# SCM (Grand Teton) — schematic netlist excerpt (pin names and nets, part order shuffled) for the footprints in the layout excerpt that follows; sources: Cadence DE-HDL packaged netlist, KiCad conversion of 12092022_DA0F0TMDCD0_F0T_Management_Board_D_brd_V3_OCP.brd

R225  Q_RES  100 1% CHIP  pkg 0402LF  page 15 : A = FM_PWR_BTN ; B = PWR_BTN_BMC_N
R27  Q_RES  0 5% EMPTY  pkg 0603LF  page 23 : A = P5V_AUX ; B = CRT_VCC5

(kicad_pcb
	(version 20260206)
	(generator "pcbnew")
	(generator_version "10.0")
	(general
		(thickness 1.6)
		(legacy_teardrops no)
	)
	(paper "A4")
	(title_block
		(title "12092022_DA0F0TMDCD0_F0T_Management_Board_D_brd_V3_OCP.brd")
		(comment 1 "Grand Teton / footprints 1274-1275 of 1440")
	)
	(layers
		(0 "F.Cu" signal "TOP")
		(4 "In1.Cu" signal "GND")
		(6 "In2.Cu" signal "IN1")
		(8 "In3.Cu" signal "GND1")
		(10 "In4.Cu" signal "IN2")
		(12 "In5.Cu" signal "VCC")
		(14 "In6.Cu" signal "VCC1")
		(16 "In7.Cu" signal "IN3")
		(18 "In8.Cu" signal "GND2")
		(20 "In9.Cu" signal "IN4")
		(22 "In10.Cu" signal "GND3")
		(2 "B.Cu" signal "BOTTOM")
		(9 "F.Adhes" user "F.Adhesive")
		(11 "B.Adhes" user "B.Adhesive")
		(13 "F.Paste" user "Package Geometry/Pastemask Top")
		(15 "B.Paste" user "Package Geometry/Pastemask Bottom")
		(5 "F.SilkS" user "Ref Des/Silkscreen Top")
		(7 "B.SilkS" user "Ref Des/Silkscreen Bottom")
		(1 "F.Mask" user "Board Geometry/Soldermask Top")
		(3 "B.Mask" user "Board Geometry/Soldermask Bottom")
		(17 "Dwgs.User" user "User.Drawings")
		(19 "Cmts.User" user "User.Comments")
		(21 "Eco1.User" user "User.Eco1")
		(23 "Eco2.User" user "User.Eco2")
		(25 "Edge.Cuts" user "Board Geometry/Outline")
		(27 "Margin" user)
		(31 "F.CrtYd" user "Package Geometry/Place Bound Top")
		(29 "B.CrtYd" user "Package Geometry/Place Bound Bottom")
		(35 "F.Fab" user "Ref Des/Assembly Top")
		(33 "B.Fab" user "Ref Des/Assembly Bottom")
	)
	(footprint ""
		(layer "B.Cu")
		(at 41.918128 -60.573666)
		(property "Reference" "R225"
			(at 0 0 0)
			(layer "B.SilkS")
			(hide yes)
			(effects
				(font
					(size 1.27 1.27)
				)
				(justify mirror)
			)
		)
		(property "Value" ""
			(at 0 0 0)
			(layer "B.Fab")
			(effects
				(font
					(size 1.27 1.27)
				)
				(justify mirror)
			)
		)
		(duplicate_pad_numbers_are_jumpers no)
		(fp_line
			(start -0.7874 -0.4064)
			(end -0.7874 0.4064)
			(stroke
				(width 0.1524)
				(type default)
			)
			(layer "B.SilkS")
		)
		(fp_line
			(start -0.7874 0.4064)
			(end 0.7874 0.4064)
			(stroke
				(width 0.1524)
				(type default)
			)
			(layer "B.SilkS")
		)
		(fp_line
			(start 0.7874 -0.4064)
			(end -0.7874 -0.4064)
			(stroke
				(width 0.1524)
				(type default)
			)
			(layer "B.SilkS")
		)
		(fp_line
			(start 0.7874 0.4064)
			(end 0.7874 -0.4064)
			(stroke
				(width 0.1524)
				(type default)
			)
			(layer "B.SilkS")
		)
		(fp_line
			(start -0.67945 -0.3048)
			(end -0.67945 0.3048)
			(stroke
				(width 0.1)
				(type default)
			)
			(layer "B.Fab")
		)
		(fp_line
			(start -0.67945 0.3048)
			(end -0.120396 0.3048)
			(stroke
				(width 0.1)
				(type default)
			)
			(layer "B.Fab")
		)
		(fp_line
			(start -0.12065 -0.3048)
			(end -0.67945 -0.3048)
			(stroke
				(width 0.1)
				(type default)
			)
			(layer "B.Fab")
		)
		(fp_line
			(start -0.12065 -0.2794)
			(end -0.12065 -0.3048)
			(stroke
				(width 0.1)
				(type default)
			)
			(layer "B.Fab")
		)
		(fp_line
			(start -0.120396 0.2794)
			(end 0.12065 0.2794)
			(stroke
				(width 0.1)
				(type default)
			)
			(layer "B.Fab")
		)
		(fp_line
			(start -0.120396 0.3048)
			(end -0.120396 0.2794)
			(stroke
				(width 0.1)
				(type default)
			)
			(layer "B.Fab")
		)
		(fp_line
			(start 0.12065 -0.305054)
			(end 0.12065 -0.2794)
			(stroke
				(width 0.1)
				(type default)
			)
			(layer "B.Fab")
		)
		(fp_line
			(start 0.12065 -0.2794)
			(end -0.12065 -0.2794)
			(stroke
				(width 0.1)
				(type default)
			)
			(layer "B.Fab")
		)
		(fp_line
			(start 0.12065 0.2794)
			(end 0.12065 0.3048)
			(stroke
				(width 0.1)
				(type default)
			)
			(layer "B.Fab")
		)
		(fp_line
			(start 0.12065 0.3048)
			(end 0.67945 0.3048)
			(stroke
				(width 0.1)
				(type default)
			)
			(layer "B.Fab")
		)
		(fp_line
			(start 0.67945 -0.305054)
			(end 0.12065 -0.305054)
			(stroke
				(width 0.1)
				(type default)
			)
			(layer "B.Fab")
		)
		(fp_line
			(start 0.67945 0.3048)
			(end 0.67945 -0.305054)
			(stroke
				(width 0.1)
				(type default)
			)
			(layer "B.Fab")
		)
		(pad "1" smd circle
			(at 0.40005 0 180)
			(size 0 0)
			(layers "B.Cu" "B.Mask" "B.Paste")
			(net "FM_PWR_BTN")
		)
		(pad "2" smd circle
			(at -0.40005 0 180)
			(size 0 0)
			(layers "B.Cu" "B.Mask" "B.Paste")
			(net "PWR_BTN_BMC_N")
		)
	)
	(footprint ""
		(layer "B.Cu")
		(at 32.96793 -38.8747 90)
		(property "Reference" "R27"
			(at 0 0 90)
			(layer "B.SilkS")
			(hide yes)
			(effects
				(font
					(size 1.27 1.27)
				)
				(justify mirror)
			)
		)
		(property "Value" ""
			(at 0 0 90)
			(layer "B.Fab")
			(effects
				(font
					(size 1.27 1.27)
				)
				(justify mirror)
			)
		)
		(duplicate_pad_numbers_are_jumpers no)
		(fp_line
			(start 1.2954 -0.5842)
			(end -1.2954 -0.5842)
			(stroke
				(width 0.1524)
				(type default)
			)
			(layer "B.SilkS")
		)
		(fp_line
			(start -1.2954 -0.5842)
			(end -1.2954 0.5842)
			(stroke
				(width 0.1524)
				(type default)
			)
			(layer "B.SilkS")
		)
		(fp_line
			(start 1.2954 0.5842)
			(end 1.2954 -0.5842)
			(stroke
				(width 0.1524)
				(type default)
			)
			(layer "B.SilkS")
		)
		(fp_line
			(start -1.2954 0.5842)
			(end 1.2954 0.5842)
			(stroke
				(width 0.1524)
				(type default)
			)
			(layer "B.SilkS")
		)
		(fp_line
			(start 0.8636 -0.4572)
			(end -0.8636 -0.4572)
			(stroke
				(width 0.1)
				(type default)
			)
			(layer "B.Fab")
		)
		(fp_line
			(start -0.8636 -0.4572)
			(end -0.8636 -0.406654)
			(stroke
				(width 0.1)
				(type default)
			)
			(layer "B.Fab")
		)
		(fp_line
			(start 1.1938 -0.406654)
			(end 0.8636 -0.406654)
			(stroke
				(width 0.1)
				(type default)
			)
			(layer "B.Fab")
		)
		(fp_line
			(start 0.8636 -0.406654)
			(end 0.8636 -0.4572)
			(stroke
				(width 0.1)
				(type default)
			)
			(layer "B.Fab")
		)
		(fp_line
			(start -0.8636 -0.406654)
			(end -1.1938 -0.406654)
			(stroke
				(width 0.1)
				(type default)
			)
			(layer "B.Fab")
		)
		(fp_line
			(start -1.1938 -0.406654)
			(end -1.1938 0.4064)
			(stroke
				(width 0.1)
				(type default)
			)
			(layer "B.Fab")
		)
		(fp_line
			(start 1.1938 0.4064)
			(end 1.1938 -0.406654)
			(stroke
				(width 0.1)
				(type default)
			)
			(layer "B.Fab")
		)
		(fp_line
			(start 0.8636 0.4064)
			(end 1.1938 0.4064)
			(stroke
				(width 0.1)
				(type default)
			)
			(layer "B.Fab")
		)
		(fp_line
			(start -0.8636 0.4064)
			(end -0.8636 0.4572)
			(stroke
				(width 0.1)
				(type default)
			)
			(layer "B.Fab")
		)
		(fp_line
			(start -1.1938 0.4064)
			(end -0.8636 0.4064)
			(stroke
				(width 0.1)
				(type default)
			)
			(layer "B.Fab")
		)
		(fp_line
			(start 0.8636 0.4318)
			(end 0.8636 0.4064)
			(stroke
				(width 0.1)
				(type default)
			)
			(layer "B.Fab")
		)
		(fp_line
			(start 0.8636 0.4572)
			(end 0.8636 0.4318)
			(stroke
				(width 0.1)
				(type default)
			)
			(layer "B.Fab")
		)
		(fp_line
			(start -0.8636 0.4572)
			(end 0.8636 0.4572)
			(stroke
				(width 0.1)
				(type default)
			)
			(layer "B.Fab")
		)
		(pad "1" smd rect
			(at 0.7366 0)
			(size 0.7112 0.8128)
			(layers "B.Cu" "B.Mask" "B.Paste")
			(net "P5V_AUX")
		)
		(pad "2" smd rect
			(at -0.7366 0)
			(size 0.7112 0.8128)
			(layers "B.Cu" "B.Mask" "B.Paste")
			(net "CRT_VCC5")
		)
	)
)
